(kicad_pcb
	(version 20260206)
	(generator "pcbnew")
	(generator_version "10.0")
	(general
		(thickness 1.6)
		(legacy_teardrops no)
	)
	(paper "A4")
	(title_block
		(title "12092022_DA0F0TMDCD0_F0T_Management_Board_D_brd_V3_OCP.brd")
		(comment 1 "Grand Teton / footprints 425-430 of 1440")
	)
	(layers
		(0 "F.Cu" signal "TOP")
		(4 "In1.Cu" signal "GND")
		(6 "In2.Cu" signal "IN1")
		(8 "In3.Cu" signal "GND1")
		(10 "In4.Cu" signal "IN2")
		(12 "In5.Cu" signal "VCC")
		(14 "In6.Cu" signal "VCC1")
		(16 "In7.Cu" signal "IN3")
		(18 "In8.Cu" signal "GND2")
		(20 "In9.Cu" signal "IN4")
		(22 "In10.Cu" signal "GND3")
		(2 "B.Cu" signal "BOTTOM")
		(9 "F.Adhes" user "F.Adhesive")
		(11 "B.Adhes" user "B.Adhesive")
		(13 "F.Paste" user "Package Geometry/Pastemask Top")
		(15 "B.Paste" user "Package Geometry/Pastemask Bottom")
		(5 "F.SilkS" user "Ref Des/Silkscreen Top")
		(7 "B.SilkS" user "Ref Des/Silkscreen Bottom")
		(1 "F.Mask" user "Board Geometry/Soldermask Top")
		(3 "B.Mask" user "Board Geometry/Soldermask Bottom")
		(17 "Dwgs.User" user "User.Drawings")
		(19 "Cmts.User" user "User.Comments")
		(21 "Eco1.User" user "User.Eco1")
		(23 "Eco2.User" user "User.Eco2")
		(25 "Edge.Cuts" user "Board Geometry/Outline")
		(27 "Margin" user)
		(31 "F.CrtYd" user "Package Geometry/Place Bound Top")
		(29 "B.CrtYd" user "Package Geometry/Place Bound Bottom")
		(35 "F.Fab" user "Ref Des/Assembly Top")
		(33 "B.Fab" user "Ref Des/Assembly Bottom")
	)
	(footprint ""
		(layer "F.Cu")
		(at 57.023 -77.3684)
		(property "Reference" "R555"
			(at 0 0 0)
			(layer "F.SilkS")
			(hide yes)
			(effects
				(font
					(size 1.27 1.27)
				)
			)
		)
		(property "Value" ""
			(at 0 0 0)
			(layer "F.Fab")
			(effects
				(font
					(size 1.27 1.27)
				)
			)
		)
		(duplicate_pad_numbers_are_jumpers no)
		(fp_line
			(start -0.7874 -0.4064)
			(end 0.7874 -0.4064)
			(stroke
				(width 0.1524)
				(type default)
			)
			(layer "F.SilkS")
		)
		(fp_line
			(start -0.7874 0.4064)
			(end -0.7874 -0.4064)
			(stroke
				(width 0.1524)
				(type default)
			)
			(layer "F.SilkS")
		)
		(fp_line
			(start 0.7874 -0.4064)
			(end 0.7874 0.4064)
			(stroke
				(width 0.1524)
				(type default)
			)
			(layer "F.SilkS")
		)
		(fp_line
			(start 0.7874 0.4064)
			(end -0.7874 0.4064)
			(stroke
				(width 0.1524)
				(type default)
			)
			(layer "F.SilkS")
		)
		(fp_line
			(start -0.67945 -0.305054)
			(end -0.12065 -0.305054)
			(stroke
				(width 0.1)
				(type default)
			)
			(layer "F.Fab")
		)
		(fp_line
			(start -0.67945 0.3048)
			(end -0.67945 -0.305054)
			(stroke
				(width 0.1)
				(type default)
			)
			(layer "F.Fab")
		)
		(fp_line
			(start -0.12065 -0.305054)
			(end -0.12065 -0.2794)
			(stroke
				(width 0.1)
				(type default)
			)
			(layer "F.Fab")
		)
		(fp_line
			(start -0.12065 -0.2794)
			(end 0.12065 -0.2794)
			(stroke
				(width 0.1)
				(type default)
			)
			(layer "F.Fab")
		)
		(fp_line
			(start -0.12065 0.2794)
			(end -0.12065 0.3048)
			(stroke
				(width 0.1)
				(type default)
			)
			(layer "F.Fab")
		)
		(fp_line
			(start -0.12065 0.3048)
			(end -0.67945 0.3048)
			(stroke
				(width 0.1)
				(type default)
			)
			(layer "F.Fab")
		)
		(fp_line
			(start 0.120396 0.2794)
			(end -0.12065 0.2794)
			(stroke
				(width 0.1)
				(type default)
			)
			(layer "F.Fab")
		)
		(fp_line
			(start 0.120396 0.3048)
			(end 0.120396 0.2794)
			(stroke
				(width 0.1)
				(type default)
			)
			(layer "F.Fab")
		)
		(fp_line
			(start 0.12065 -0.3048)
			(end 0.67945 -0.3048)
			(stroke
				(width 0.1)
				(type default)
			)
			(layer "F.Fab")
		)
		(fp_line
			(start 0.12065 -0.2794)
			(end 0.12065 -0.3048)
			(stroke
				(width 0.1)
				(type default)
			)
			(layer "F.Fab")
		)
		(fp_line
			(start 0.67945 -0.3048)
			(end 0.67945 0.3048)
			(stroke
				(width 0.1)
				(type default)
			)
			(layer "F.Fab")
		)
		(fp_line
			(start 0.67945 0.3048)
			(end 0.120396 0.3048)
			(stroke
				(width 0.1)
				(type default)
			)
			(layer "F.Fab")
		)
		(pad "1" smd circle
			(at -0.40005 0)
			(size 0 0)
			(layers "F.Cu" "F.Mask" "F.Paste")
			(net "FLASH_LATCH_Q_N_R")
		)
		(pad "2" smd circle
			(at 0.40005 0)
			(size 0 0)
			(layers "F.Cu" "F.Mask" "F.Paste")
			(net "FLASH_LATCH_Q_N_R1")
		)
	)
	(footprint ""
		(layer "F.Cu")
		(at 46.6852 -30.861 -90)
		(property "Reference" "R60"
			(at 0 0 270)
			(layer "F.SilkS")
			(hide yes)
			(effects
				(font
					(size 1.27 1.27)
				)
			)
		)
		(property "Value" ""
			(at 0 0 270)
			(layer "F.Fab")
			(effects
				(font
					(size 1.27 1.27)
				)
			)
		)
		(duplicate_pad_numbers_are_jumpers no)
		(fp_line
			(start -0.7874 0.4064)
			(end -0.7874 -0.4064)
			(stroke
				(width 0.1524)
				(type default)
			)
			(layer "F.SilkS")
		)
		(fp_line
			(start 0.7874 0.4064)
			(end -0.7874 0.4064)
			(stroke
				(width 0.1524)
				(type default)
			)
			(layer "F.SilkS")
		)
		(fp_line
			(start -0.7874 -0.4064)
			(end 0.7874 -0.4064)
			(stroke
				(width 0.1524)
				(type default)
			)
			(layer "F.SilkS")
		)
		(fp_line
			(start 0.7874 -0.4064)
			(end 0.7874 0.4064)
			(stroke
				(width 0.1524)
				(type default)
			)
			(layer "F.SilkS")
		)
		(fp_line
			(start -0.67945 0.3048)
			(end -0.67945 -0.305054)
			(stroke
				(width 0.1)
				(type default)
			)
			(layer "F.Fab")
		)
		(fp_line
			(start -0.12065 0.3048)
			(end -0.67945 0.3048)
			(stroke
				(width 0.1)
				(type default)
			)
			(layer "F.Fab")
		)
		(fp_line
			(start 0.120396 0.3048)
			(end 0.120396 0.2794)
			(stroke
				(width 0.1)
				(type default)
			)
			(layer "F.Fab")
		)
		(fp_line
			(start 0.67945 0.3048)
			(end 0.120396 0.3048)
			(stroke
				(width 0.1)
				(type default)
			)
			(layer "F.Fab")
		)
		(fp_line
			(start -0.12065 0.2794)
			(end -0.12065 0.3048)
			(stroke
				(width 0.1)
				(type default)
			)
			(layer "F.Fab")
		)
		(fp_line
			(start 0.120396 0.2794)
			(end -0.12065 0.2794)
			(stroke
				(width 0.1)
				(type default)
			)
			(layer "F.Fab")
		)
		(fp_line
			(start -0.12065 -0.2794)
			(end 0.12065 -0.2794)
			(stroke
				(width 0.1)
				(type default)
			)
			(layer "F.Fab")
		)
		(fp_line
			(start 0.12065 -0.2794)
			(end 0.12065 -0.3048)
			(stroke
				(width 0.1)
				(type default)
			)
			(layer "F.Fab")
		)
		(fp_line
			(start 0.12065 -0.3048)
			(end 0.67945 -0.3048)
			(stroke
				(width 0.1)
				(type default)
			)
			(layer "F.Fab")
		)
		(fp_line
			(start 0.67945 -0.3048)
			(end 0.67945 0.3048)
			(stroke
				(width 0.1)
				(type default)
			)
			(layer "F.Fab")
		)
		(fp_line
			(start -0.67945 -0.305054)
			(end -0.12065 -0.305054)
			(stroke
				(width 0.1)
				(type default)
			)
			(layer "F.Fab")
		)
		(fp_line
			(start -0.12065 -0.305054)
			(end -0.12065 -0.2794)
			(stroke
				(width 0.1)
				(type default)
			)
			(layer "F.Fab")
		)
		(pad "1" smd circle
			(at -0.40005 0 270)
			(size 0 0)
			(layers "F.Cu" "F.Mask" "F.Paste")
			(net "RST_ROT_CPU_R1_N")
		)
		(pad "2" smd circle
			(at 0.40005 0 270)
			(size 0 0)
			(layers "F.Cu" "F.Mask" "F.Paste")
			(net "RST_ROT_CPU_N")
		)
	)
	(footprint ""
		(layer "F.Cu")
		(at 58.7248 -65.5828)
		(property "Reference" "R683"
			(at 0 0 0)
			(layer "F.SilkS")
			(hide yes)
			(effects
				(font
					(size 1.27 1.27)
				)
			)
		)
		(property "Value" ""
			(at 0 0 0)
			(layer "F.Fab")
			(effects
				(font
					(size 1.27 1.27)
				)
			)
		)
		(duplicate_pad_numbers_are_jumpers no)
		(fp_line
			(start -0.7874 -0.4064)
			(end 0.7874 -0.4064)
			(stroke
				(width 0.1524)
				(type default)
			)
			(layer "F.SilkS")
		)
		(fp_line
			(start -0.7874 0.4064)
			(end -0.7874 -0.4064)
			(stroke
				(width 0.1524)
				(type default)
			)
			(layer "F.SilkS")
		)
		(fp_line
			(start 0.7874 -0.4064)
			(end 0.7874 0.4064)
			(stroke
				(width 0.1524)
				(type default)
			)
			(layer "F.SilkS")
		)
		(fp_line
			(start 0.7874 0.4064)
			(end -0.7874 0.4064)
			(stroke
				(width 0.1524)
				(type default)
			)
			(layer "F.SilkS")
		)
		(fp_line
			(start -0.67945 -0.305054)
			(end -0.12065 -0.305054)
			(stroke
				(width 0.1)
				(type default)
			)
			(layer "F.Fab")
		)
		(fp_line
			(start -0.67945 0.3048)
			(end -0.67945 -0.305054)
			(stroke
				(width 0.1)
				(type default)
			)
			(layer "F.Fab")
		)
		(fp_line
			(start -0.12065 -0.305054)
			(end -0.12065 -0.2794)
			(stroke
				(width 0.1)
				(type default)
			)
			(layer "F.Fab")
		)
		(fp_line
			(start -0.12065 -0.2794)
			(end 0.12065 -0.2794)
			(stroke
				(width 0.1)
				(type default)
			)
			(layer "F.Fab")
		)
		(fp_line
			(start -0.12065 0.2794)
			(end -0.12065 0.3048)
			(stroke
				(width 0.1)
				(type default)
			)
			(layer "F.Fab")
		)
		(fp_line
			(start -0.12065 0.3048)
			(end -0.67945 0.3048)
			(stroke
				(width 0.1)
				(type default)
			)
			(layer "F.Fab")
		)
		(fp_line
			(start 0.120396 0.2794)
			(end -0.12065 0.2794)
			(stroke
				(width 0.1)
				(type default)
			)
			(layer "F.Fab")
		)
		(fp_line
			(start 0.120396 0.3048)
			(end 0.120396 0.2794)
			(stroke
				(width 0.1)
				(type default)
			)
			(layer "F.Fab")
		)
		(fp_line
			(start 0.12065 -0.3048)
			(end 0.67945 -0.3048)
			(stroke
				(width 0.1)
				(type default)
			)
			(layer "F.Fab")
		)
		(fp_line
			(start 0.12065 -0.2794)
			(end 0.12065 -0.3048)
			(stroke
				(width 0.1)
				(type default)
			)
			(layer "F.Fab")
		)
		(fp_line
			(start 0.67945 -0.3048)
			(end 0.67945 0.3048)
			(stroke
				(width 0.1)
				(type default)
			)
			(layer "F.Fab")
		)
		(fp_line
			(start 0.67945 0.3048)
			(end 0.120396 0.3048)
			(stroke
				(width 0.1)
				(type default)
			)
			(layer "F.Fab")
		)
		(pad "1" smd circle
			(at -0.40005 0)
			(size 0 0)
			(layers "F.Cu" "F.Mask" "F.Paste")
			(net "P3V3_AUX")
		)
		(pad "2" smd circle
			(at 0.40005 0)
			(size 0 0)
			(layers "F.Cu" "F.Mask" "F.Paste")
			(net "PU_SPI1WP_N")
		)
	)
	(footprint ""
		(layer "F.Cu")
		(at 29.2608 -30.099)
		(property "Reference" "L29"
			(at 0 0 0)
			(layer "F.SilkS")
			(hide yes)
			(effects
				(font
					(size 1.27 1.27)
				)
			)
		)
		(property "Value" ""
			(at 0 0 0)
			(layer "F.Fab")
			(effects
				(font
					(size 1.27 1.27)
				)
			)
		)
		(duplicate_pad_numbers_are_jumpers no)
		(fp_line
			(start -1.27 -0.5842)
			(end 1.27 -0.5842)
			(stroke
				(width 0.1524)
				(type default)
			)
			(layer "F.SilkS")
		)
		(fp_line
			(start -1.27 -0.5588)
			(end -1.27 -0.5842)
			(stroke
				(width 0.1524)
				(type default)
			)
			(layer "F.SilkS")
		)
		(fp_line
			(start -1.27 0.5842)
			(end -1.27 -0.5842)
			(stroke
				(width 0.1524)
				(type default)
			)
			(layer "F.SilkS")
		)
		(fp_line
			(start -0.127 0.5842)
			(end -0.127 -0.5842)
			(stroke
				(width 0.1524)
				(type default)
			)
			(layer "F.SilkS")
		)
		(fp_line
			(start 0.127 0.5842)
			(end 0.127 -0.5842)
			(stroke
				(width 0.1524)
				(type default)
			)
			(layer "F.SilkS")
		)
		(fp_line
			(start 1.27 0.5842)
			(end -1.27 0.5842)
			(stroke
				(width 0.1524)
				(type default)
			)
			(layer "F.SilkS")
		)
		(fp_line
			(start 1.27 0.5842)
			(end 1.27 -0.5842)
			(stroke
				(width 0.1524)
				(type default)
			)
			(layer "F.SilkS")
		)
		(fp_line
			(start -1.194308 -0.406654)
			(end -0.9144 -0.406654)
			(stroke
				(width 0.1)
				(type default)
			)
			(layer "F.Fab")
		)
		(fp_line
			(start -1.194308 0.406654)
			(end -1.194308 -0.406654)
			(stroke
				(width 0.1)
				(type default)
			)
			(layer "F.Fab")
		)
		(fp_line
			(start -0.9144 -0.508)
			(end 0.9144 -0.508)
			(stroke
				(width 0.1)
				(type default)
			)
			(layer "F.Fab")
		)
		(fp_line
			(start -0.9144 -0.406654)
			(end -0.9144 -0.508)
			(stroke
				(width 0.1)
				(type default)
			)
			(layer "F.Fab")
		)
		(fp_line
			(start -0.9144 0.406654)
			(end -1.194308 0.406654)
			(stroke
				(width 0.1)
				(type default)
			)
			(layer "F.Fab")
		)
		(fp_line
			(start -0.9144 0.508)
			(end -0.9144 0.406654)
			(stroke
				(width 0.1)
				(type default)
			)
			(layer "F.Fab")
		)
		(fp_line
			(start 0.9144 -0.508)
			(end 0.9144 -0.406654)
			(stroke
				(width 0.1)
				(type default)
			)
			(layer "F.Fab")
		)
		(fp_line
			(start 0.9144 -0.406654)
			(end 1.1938 -0.406654)
			(stroke
				(width 0.1)
				(type default)
			)
			(layer "F.Fab")
		)
		(fp_line
			(start 0.9144 0.4064)
			(end 0.9144 0.508)
			(stroke
				(width 0.1)
				(type default)
			)
			(layer "F.Fab")
		)
		(fp_line
			(start 0.9144 0.508)
			(end -0.9144 0.508)
			(stroke
				(width 0.1)
				(type default)
			)
			(layer "F.Fab")
		)
		(fp_line
			(start 1.1938 -0.406654)
			(end 1.1938 0.4064)
			(stroke
				(width 0.1)
				(type default)
			)
			(layer "F.Fab")
		)
		(fp_line
			(start 1.1938 0.4064)
			(end 0.9144 0.4064)
			(stroke
				(width 0.1)
				(type default)
			)
			(layer "F.Fab")
		)
		(pad "1" smd rect
			(at -0.7366 0 270)
			(size 0.7112 0.8128)
			(layers "F.Cu" "F.Mask" "F.Paste")
			(net "V_DACG")
		)
		(pad "2" smd rect
			(at 0.7366 0 270)
			(size 0.7112 0.8128)
			(layers "F.Cu" "F.Mask" "F.Paste")
			(net "V_DACG_IO")
		)
	)
	(footprint ""
		(layer "F.Cu")
		(at 81.818988 -59.05373 -90)
		(property "Reference" "PC257"
			(at 0 0 270)
			(layer "F.SilkS")
			(hide yes)
			(effects
				(font
					(size 1.27 1.27)
				)
			)
		)
		(property "Value" ""
			(at 0 0 270)
			(layer "F.Fab")
			(effects
				(font
					(size 1.27 1.27)
				)
			)
		)
		(duplicate_pad_numbers_are_jumpers no)
		(fp_line
			(start -1.651 0.8382)
			(end -1.651 -0.8382)
			(stroke
				(width 0.1524)
				(type default)
			)
			(layer "F.SilkS")
		)
		(fp_line
			(start 0 0.8382)
			(end 0 -0.8382)
			(stroke
				(width 0.1524)
				(type default)
			)
			(layer "F.SilkS")
		)
		(fp_line
			(start 1.651 0.8382)
			(end -1.651 0.8382)
			(stroke
				(width 0.1524)
				(type default)
			)
			(layer "F.SilkS")
		)
		(fp_line
			(start -1.651 -0.8382)
			(end 1.651 -0.8382)
			(stroke
				(width 0.1524)
				(type default)
			)
			(layer "F.SilkS")
		)
		(fp_line
			(start 1.651 -0.8382)
			(end 1.651 0.8382)
			(stroke
				(width 0.1524)
				(type default)
			)
			(layer "F.SilkS")
		)
		(fp_line
			(start -1.55956 0.7366)
			(end -1.524 0.7366)
			(stroke
				(width 0.1)
				(type default)
			)
			(layer "F.Fab")
		)
		(fp_line
			(start -1.524 0.7366)
			(end 1.524 0.7366)
			(stroke
				(width 0.1)
				(type default)
			)
			(layer "F.Fab")
		)
		(fp_line
			(start 1.524 0.7366)
			(end 1.55956 0.7366)
			(stroke
				(width 0.1)
				(type default)
			)
			(layer "F.Fab")
		)
		(fp_line
			(start 1.55956 0.7366)
			(end 1.55956 -0.7366)
			(stroke
				(width 0.1)
				(type default)
			)
			(layer "F.Fab")
		)
		(fp_line
			(start -1.55956 -0.7366)
			(end -1.55956 0.7366)
			(stroke
				(width 0.1)
				(type default)
			)
			(layer "F.Fab")
		)
		(fp_line
			(start -1.524 -0.7366)
			(end -1.55956 -0.7366)
			(stroke
				(width 0.1)
				(type default)
			)
			(layer "F.Fab")
		)
		(fp_line
			(start 1.524 -0.7366)
			(end -1.524 -0.7366)
			(stroke
				(width 0.1)
				(type default)
			)
			(layer "F.Fab")
		)
		(fp_line
			(start 1.55956 -0.7366)
			(end 1.524 -0.7366)
			(stroke
				(width 0.1)
				(type default)
			)
			(layer "F.Fab")
		)
		(pad "1" smd rect
			(at -0.94996 0 90)
			(size 1.1176 1.3716)
			(layers "F.Cu" "F.Mask" "F.Paste")
			(net "P1V2_AUX")
		)
		(pad "2" smd rect
			(at 0.94996 0 90)
			(size 1.1176 1.3716)
			(layers "F.Cu" "F.Mask" "F.Paste")
			(net "GND")
		)
	)
	(footprint ""
		(layer "F.Cu")
		(at 20.701 -42.9006 -90)
		(property "Reference" "R752"
			(at 0 0 270)
			(layer "F.SilkS")
			(hide yes)
			(effects
				(font
					(size 1.27 1.27)
				)
			)
		)
		(property "Value" ""
			(at 0 0 270)
			(layer "F.Fab")
			(effects
				(font
					(size 1.27 1.27)
				)
			)
		)
		(duplicate_pad_numbers_are_jumpers no)
		(fp_line
			(start -0.7874 0.4064)
			(end -0.7874 -0.4064)
			(stroke
				(width 0.1524)
				(type default)
			)
			(layer "F.SilkS")
		)
		(fp_line
			(start 0.7874 0.4064)
			(end -0.7874 0.4064)
			(stroke
				(width 0.1524)
				(type default)
			)
			(layer "F.SilkS")
		)
		(fp_line
			(start -0.7874 -0.4064)
			(end 0.7874 -0.4064)
			(stroke
				(width 0.1524)
				(type default)
			)
			(layer "F.SilkS")
		)
		(fp_line
			(start 0.7874 -0.4064)
			(end 0.7874 0.4064)
			(stroke
				(width 0.1524)
				(type default)
			)
			(layer "F.SilkS")
		)
		(fp_line
			(start -0.67945 0.3048)
			(end -0.67945 -0.305054)
			(stroke
				(width 0.1)
				(type default)
			)
			(layer "F.Fab")
		)
		(fp_line
			(start -0.12065 0.3048)
			(end -0.67945 0.3048)
			(stroke
				(width 0.1)
				(type default)
			)
			(layer "F.Fab")
		)
		(fp_line
			(start 0.120396 0.3048)
			(end 0.120396 0.2794)
			(stroke
				(width 0.1)
				(type default)
			)
			(layer "F.Fab")
		)
		(fp_line
			(start 0.67945 0.3048)
			(end 0.120396 0.3048)
			(stroke
				(width 0.1)
				(type default)
			)
			(layer "F.Fab")
		)
		(fp_line
			(start -0.12065 0.2794)
			(end -0.12065 0.3048)
			(stroke
				(width 0.1)
				(type default)
			)
			(layer "F.Fab")
		)
		(fp_line
			(start 0.120396 0.2794)
			(end -0.12065 0.2794)
			(stroke
				(width 0.1)
				(type default)
			)
			(layer "F.Fab")
		)
		(fp_line
			(start -0.12065 -0.2794)
			(end 0.12065 -0.2794)
			(stroke
				(width 0.1)
				(type default)
			)
			(layer "F.Fab")
		)
		(fp_line
			(start 0.12065 -0.2794)
			(end 0.12065 -0.3048)
			(stroke
				(width 0.1)
				(type default)
			)
			(layer "F.Fab")
		)
		(fp_line
			(start 0.12065 -0.3048)
			(end 0.67945 -0.3048)
			(stroke
				(width 0.1)
				(type default)
			)
			(layer "F.Fab")
		)
		(fp_line
			(start 0.67945 -0.3048)
			(end 0.67945 0.3048)
			(stroke
				(width 0.1)
				(type default)
			)
			(layer "F.Fab")
		)
		(fp_line
			(start -0.67945 -0.305054)
			(end -0.12065 -0.305054)
			(stroke
				(width 0.1)
				(type default)
			)
			(layer "F.Fab")
		)
		(fp_line
			(start -0.12065 -0.305054)
			(end -0.12065 -0.2794)
			(stroke
				(width 0.1)
				(type default)
			)
			(layer "F.Fab")
		)
		(pad "1" smd circle
			(at -0.40005 0 270)
			(size 0 0)
			(layers "F.Cu" "F.Mask" "F.Paste")
			(net "RST_SPI_FLASH_N")
		)
		(pad "2" smd circle
			(at 0.40005 0 270)
			(size 0 0)
			(layers "F.Cu" "F.Mask" "F.Paste")
			(net "RST_SPI_FLASH_R_N")
		)
	)
)
